(kicad_pcb
	(version 20241229)
	(generator "pcbnew")
	(generator_version "9.0")
	(general
		(thickness 1.552)
		(legacy_teardrops no)
	)
	(paper "A4")
	(title_block
		(date "2023-07-25")
		(rev "1.1.4")
		(comment 9 "footprints 275-280 of 379")
	)
	(layers
		(0 "F.Cu" signal)
		(4 "In1.Cu" signal)
		(6 "In2.Cu" signal)
		(8 "In3.Cu" signal)
		(10 "In4.Cu" signal)
		(12 "In5.Cu" signal)
		(14 "In6.Cu" signal)
		(2 "B.Cu" signal)
		(9 "F.Adhes" user "F.Adhesive")
		(11 "B.Adhes" user "B.Adhesive")
		(13 "F.Paste" user)
		(15 "B.Paste" user)
		(5 "F.SilkS" user "F.Silkscreen")
		(7 "B.SilkS" user "B.Silkscreen")
		(1 "F.Mask" user)
		(3 "B.Mask" user)
		(17 "Dwgs.User" user "User.Drawings")
		(19 "Cmts.User" user "User.Comments")
		(21 "Eco1.User" user "User.Eco1")
		(23 "Eco2.User" user "User.Eco2")
		(25 "Edge.Cuts" user)
		(27 "Margin" user)
		(31 "F.CrtYd" user "F.Courtyard")
		(29 "B.CrtYd" user "B.Courtyard")
		(35 "F.Fab" user)
		(33 "B.Fab" user)
	)
	(footprint "antmicro-footprints:C_0402_1005Metric"
		(layer "B.Cu")
		(at 97.39 74.66 -90)
		(descr "Capacitor SMD 0402")
		(tags "capacitor SMD 0402")
		(property "Reference" "C61"
			(at -0.92 -1.35 90)
			(layer "B.SilkS")
			(effects
				(font
					(size 0.65 0.65)
					(thickness 0.15)
				)
				(justify left bottom mirror)
			)
		)
		(property "Value" "C_100n_0402"
			(at 0 -1.4 90)
			(layer "B.Fab")
			(hide yes)
			(effects
				(font
					(size 0.7 0.7)
					(thickness 0.15)
				)
				(justify left bottom mirror)
			)
		)
		(property "Datasheet" "https://www.murata.com/products/productdetail?partno=GRM155R61H104KE14%23"
			(at 0 0 270)
			(layer "F.Fab")
			(hide yes)
			(effects
				(font
					(size 1.27 1.27)
					(thickness 0.15)
				)
			)
		)
		(property "Description" "SMD Multilayer Ceramic Capacitor, 0.1 µF, 50 V, 0402 [1005 Metric], ± 10%, X5R, GRM Series"
			(at 0 0 270)
			(layer "F.Fab")
			(hide yes)
			(effects
				(font
					(size 1.27 1.27)
					(thickness 0.15)
				)
			)
		)
		(property "Author" "Antmicro"
			(at 22.72 172.04 0)
			(layer "B.Fab")
			(hide yes)
			(effects
				(font
					(size 1 1)
					(thickness 0.15)
				)
				(justify mirror)
			)
		)
		(property "Dielectric" "X5R"
			(at 22.72 172.04 0)
			(layer "B.Fab")
			(hide yes)
			(effects
				(font
					(size 1 1)
					(thickness 0.15)
				)
				(justify mirror)
			)
		)
		(property "License" "Apache-2.0"
			(at 22.72 172.04 0)
			(layer "B.Fab")
			(hide yes)
			(effects
				(font
					(size 1 1)
					(thickness 0.15)
				)
				(justify mirror)
			)
		)
		(property "MPN" "GRM155R61H104KE14D"
			(at 22.72 172.04 0)
			(layer "B.Fab")
			(hide yes)
			(effects
				(font
					(size 1 1)
					(thickness 0.15)
				)
				(justify mirror)
			)
		)
		(property "Manufacturer" "Murata"
			(at 22.72 172.04 0)
			(layer "B.Fab")
			(hide yes)
			(effects
				(font
					(size 1 1)
					(thickness 0.15)
				)
				(justify mirror)
			)
		)
		(property "Val" "100n"
			(at 22.72 172.04 0)
			(layer "B.Fab")
			(hide yes)
			(effects
				(font
					(size 1 1)
					(thickness 0.15)
				)
				(justify mirror)
			)
		)
		(property "Voltage" "50V"
			(at 22.72 172.04 0)
			(layer "B.Fab")
			(hide yes)
			(effects
				(font
					(size 1 1)
					(thickness 0.15)
				)
				(justify mirror)
			)
		)
		(sheetname "/SDI/")
		(sheetfile "sdi.kicad_sch")
		(attr smd)
		(fp_rect
			(start -0.925 0.47)
			(end 0.925 -0.47)
			(stroke
				(width 0.05)
				(type default)
			)
			(fill no)
			(layer "B.CrtYd")
		)
		(fp_line
			(start -0.494 0.25)
			(end 0.504 0.25)
			(stroke
				(width 0.15)
				(type solid)
			)
			(layer "B.Fab")
		)
		(fp_line
			(start 0.504 0.25)
			(end 0.504 -0.248)
			(stroke
				(width 0.15)
				(type solid)
			)
			(layer "B.Fab")
		)
		(fp_line
			(start -0.494 -0.248)
			(end -0.494 0.25)
			(stroke
				(width 0.15)
				(type solid)
			)
			(layer "B.Fab")
		)
		(fp_line
			(start 0.504 -0.248)
			(end -0.494 -0.248)
			(stroke
				(width 0.15)
				(type solid)
			)
			(layer "B.Fab")
		)
		(fp_text user "License: Apache-2.0"
			(at -0.939 -5.799 90)
			(layer "B.Fab")
			(effects
				(font
					(size 0.7 0.7)
					(thickness 0.15)
				)
				(justify left bottom mirror)
			)
		)
		(fp_text user "Author: Antmicro"
			(at -0.939 -3.399 90)
			(layer "B.Fab")
			(effects
				(font
					(size 0.7 0.7)
					(thickness 0.15)
				)
				(justify left bottom mirror)
			)
		)
		(fp_text user "${REFERENCE}"
			(at -0.939 -4.599 90)
			(layer "B.Fab")
			(effects
				(font
					(size 0.7 0.7)
					(thickness 0.15)
				)
				(justify left bottom mirror)
			)
		)
		(pad "1" smd roundrect
			(at -0.48 0 270)
			(size 0.59 0.64)
			(layers "B.Cu" "B.Mask" "B.Paste")
			(roundrect_rratio 0.25)
			(net 1 "GND")
			(pintype "passive")
		)
		(pad "2" smd roundrect
			(at 0.48 0 270)
			(size 0.59 0.64)
			(layers "B.Cu" "B.Mask" "B.Paste")
			(roundrect_rratio 0.25)
			(net 3 "+1V2")
			(pintype "passive")
		)
	)
	(footprint "antmicro-footprints:TP_SMD_0.75mm"
		(layer "B.Cu")
		(at 93.1392 88.95 90)
		(property "Reference" "TP31"
			(at -2.99 0.3908 90)
			(layer "B.SilkS")
			(effects
				(font
					(size 0.65 0.65)
					(thickness 0.15)
				)
				(justify right bottom mirror)
			)
		)
		(property "Value" "TP_0.75mm_SMD"
			(at 0 -1.2 90)
			(layer "B.Fab")
			(hide yes)
			(effects
				(font
					(size 0.7 0.7)
					(thickness 0.15)
				)
				(justify right bottom mirror)
			)
		)
		(property "Description" "SMT test point"
			(at 0 0 90)
			(layer "F.Fab")
			(hide yes)
			(effects
				(font
					(size 1.27 1.27)
					(thickness 0.15)
				)
			)
		)
		(property "Author" "Antmicro"
			(at 182.0892 -4.1892 0)
			(layer "B.Fab")
			(hide yes)
			(effects
				(font
					(size 1 1)
					(thickness 0.15)
				)
				(justify mirror)
			)
		)
		(property "License" "Apache-2.0"
			(at 182.0892 -4.1892 0)
			(layer "B.Fab")
			(hide yes)
			(effects
				(font
					(size 1 1)
					(thickness 0.15)
				)
				(justify mirror)
			)
		)
		(property "MPN" ""
			(at 182.0892 -4.1892 0)
			(layer "B.Fab")
			(hide yes)
			(effects
				(font
					(size 1 1)
					(thickness 0.15)
				)
				(justify mirror)
			)
		)
		(property "Manufacturer" ""
			(at 182.0892 -4.1892 0)
			(layer "B.Fab")
			(hide yes)
			(effects
				(font
					(size 1 1)
					(thickness 0.15)
				)
				(justify mirror)
			)
		)
		(sheetname "/SDI/")
		(sheetfile "sdi.kicad_sch")
		(attr exclude_from_pos_files)
		(fp_circle
			(center 0 0)
			(end 0.475 0)
			(stroke
				(width 0.05)
				(type default)
			)
			(fill no)
			(layer "B.CrtYd")
		)
		(fp_text user "License: Apache-2.0"
			(at -0.4 -5.101 270)
			(layer "B.Fab")
			(effects
				(font
					(size 0.7 0.7)
					(thickness 0.15)
				)
				(justify left bottom mirror)
			)
		)
		(fp_text user "Author: Antmicro"
			(at -0.4 -3.901 270)
			(layer "B.Fab")
			(effects
				(font
					(size 0.7 0.7)
					(thickness 0.15)
				)
				(justify left bottom mirror)
			)
		)
		(fp_text user "${REFERENCE}"
			(at -0.4 -2.7 270)
			(layer "B.Fab")
			(effects
				(font
					(size 0.7 0.7)
					(thickness 0.15)
				)
				(justify left bottom mirror)
			)
		)
		(pad "1" smd circle
			(at 0 0 90)
			(size 0.75 0.75)
			(layers "B.Cu" "B.Mask")
			(net 198 "/SDI/AUDIO_EN{slash}~{DIS}")
			(pinfunction "1")
			(pintype "passive")
		)
	)
	(footprint "antmicro-footprints:TP_SMD_0.75mm"
		(layer "B.Cu")
		(at 96.2408 88.95 -90)
		(property "Reference" "TP41"
			(at 0.49 -0.2892 90)
			(layer "B.SilkS")
			(effects
				(font
					(size 0.65 0.65)
					(thickness 0.15)
				)
				(justify left bottom mirror)
			)
		)
		(property "Value" "TP_0.75mm_SMD"
			(at 0 -1.2 90)
			(layer "B.Fab")
			(hide yes)
			(effects
				(font
					(size 0.7 0.7)
					(thickness 0.15)
				)
				(justify left bottom mirror)
			)
		)
		(property "Description" "SMT test point"
			(at 0 0 270)
			(layer "F.Fab")
			(hide yes)
			(effects
				(font
					(size 1.27 1.27)
					(thickness 0.15)
				)
			)
		)
		(property "Author" "Antmicro"
			(at 7.2908 185.1908 0)
			(layer "B.Fab")
			(hide yes)
			(effects
				(font
					(size 1 1)
					(thickness 0.15)
				)
				(justify mirror)
			)
		)
		(property "License" "Apache-2.0"
			(at 7.2908 185.1908 0)
			(layer "B.Fab")
			(hide yes)
			(effects
				(font
					(size 1 1)
					(thickness 0.15)
				)
				(justify mirror)
			)
		)
		(property "MPN" ""
			(at 7.2908 185.1908 0)
			(layer "B.Fab")
			(hide yes)
			(effects
				(font
					(size 1 1)
					(thickness 0.15)
				)
				(justify mirror)
			)
		)
		(property "Manufacturer" ""
			(at 7.2908 185.1908 0)
			(layer "B.Fab")
			(hide yes)
			(effects
				(font
					(size 1 1)
					(thickness 0.15)
				)
				(justify mirror)
			)
		)
		(sheetname "/SDI/")
		(sheetfile "sdi.kicad_sch")
		(attr exclude_from_pos_files)
		(fp_circle
			(center 0 0)
			(end 0.475 0)
			(stroke
				(width 0.05)
				(type default)
			)
			(fill no)
			(layer "B.CrtYd")
		)
		(fp_text user "${REFERENCE}"
			(at -0.4 -2.7 90)
			(layer "B.Fab")
			(effects
				(font
					(size 0.7 0.7)
					(thickness 0.15)
				)
				(justify left bottom mirror)
			)
		)
		(fp_text user "License: Apache-2.0"
			(at -0.4 -5.101 90)
			(layer "B.Fab")
			(effects
				(font
					(size 0.7 0.7)
					(thickness 0.15)
				)
				(justify left bottom mirror)
			)
		)
		(fp_text user "Author: Antmicro"
			(at -0.4 -3.901 90)
			(layer "B.Fab")
			(effects
				(font
					(size 0.7 0.7)
					(thickness 0.15)
				)
				(justify left bottom mirror)
			)
		)
		(pad "1" smd circle
			(at 0 0 270)
			(size 0.75 0.75)
			(layers "B.Cu" "B.Mask")
			(net 177 "/SDI/SW_EN")
			(pinfunction "1")
			(pintype "passive")
		)
	)
	(footprint "antmicro-footprints:C_0201"
		(layer "B.Cu")
		(at 133.4 83.24)
		(descr "Capacitor SMD 0201")
		(tags "capacitor SMD 0201")
		(property "Reference" "C40"
			(at -0.87 -0.6 0)
			(layer "B.SilkS")
			(effects
				(font
					(size 0.65 0.65)
					(thickness 0.15)
				)
				(justify right bottom mirror)
			)
		)
		(property "Value" "C_100n_0201"
			(at 0 -1.4 0)
			(layer "B.Fab")
			(hide yes)
			(effects
				(font
					(size 0.7 0.7)
					(thickness 0.15)
				)
				(justify right bottom mirror)
			)
		)
		(property "Datasheet" "https://www.yageo.com/en/Chart/Download/pdf/CC0201KRX6S5BB104"
			(at 0 0 0)
			(layer "F.Fab")
			(hide yes)
			(effects
				(font
					(size 1.27 1.27)
					(thickness 0.15)
				)
			)
		)
		(property "Description" "SMD Multilayer Ceramic Capacitor, 0.1 µF, 6.3 V, 0201 [0603 Metric], ± 10%, X6S, CC Series"
			(at 0 0 0)
			(layer "F.Fab")
			(hide yes)
			(effects
				(font
					(size 1.27 1.27)
					(thickness 0.15)
				)
			)
		)
		(property "Author" "Antmicro"
			(at 0 0 0)
			(layer "B.Fab")
			(hide yes)
			(effects
				(font
					(size 1 1)
					(thickness 0.15)
				)
				(justify mirror)
			)
		)
		(property "Dielectric" ""
			(at 0 0 0)
			(layer "B.Fab")
			(hide yes)
			(effects
				(font
					(size 1 1)
					(thickness 0.15)
				)
				(justify mirror)
			)
		)
		(property "License" "Apache-2.0"
			(at 0 0 0)
			(layer "B.Fab")
			(hide yes)
			(effects
				(font
					(size 1 1)
					(thickness 0.15)
				)
				(justify mirror)
			)
		)
		(property "MPN" "CC0201KRX6S5BB104"
			(at 0 0 0)
			(layer "B.Fab")
			(hide yes)
			(effects
				(font
					(size 1 1)
					(thickness 0.15)
				)
				(justify mirror)
			)
		)
		(property "Manufacturer" "YAGEO"
			(at 0 0 0)
			(layer "B.Fab")
			(hide yes)
			(effects
				(font
					(size 1 1)
					(thickness 0.15)
				)
				(justify mirror)
			)
		)
		(property "Val" "100n"
			(at 0 0 0)
			(layer "B.Fab")
			(hide yes)
			(effects
				(font
					(size 1 1)
					(thickness 0.15)
				)
				(justify mirror)
			)
		)
		(property "Voltage" ""
			(at 0 0 0)
			(layer "B.Fab")
			(hide yes)
			(effects
				(font
					(size 1 1)
					(thickness 0.15)
				)
				(justify mirror)
			)
		)
		(property "Public" "False"
			(at 0 0 0)
			(unlocked yes)
			(layer "B.Fab")
			(hide yes)
			(effects
				(font
					(size 1 1)
					(thickness 0.15)
				)
				(justify mirror)
			)
		)
		(sheetname "/DDR3/")
		(sheetfile "ddr3.kicad_sch")
		(attr smd)
		(fp_rect
			(start -0.7 0.35)
			(end 0.7 -0.35)
			(stroke
				(width 0.05)
				(type default)
			)
			(fill no)
			(layer "B.CrtYd")
		)
		(fp_rect
			(start 0.3 -0.15)
			(end -0.301 0.149)
			(stroke
				(width 0.15)
				(type solid)
			)
			(fill no)
			(layer "B.Fab")
		)
		(fp_text user "${REFERENCE}"
			(at -0.72 -3.4 180)
			(layer "B.Fab")
			(effects
				(font
					(size 0.7 0.7)
					(thickness 0.15)
				)
				(justify left bottom mirror)
			)
		)
		(fp_text user "Author: Antmicro"
			(at -0.72 -5.4 180)
			(layer "B.Fab")
			(effects
				(font
					(size 0.7 0.7)
					(thickness 0.15)
				)
				(justify left bottom mirror)
			)
		)
		(fp_text user "License: Apache-2.0"
			(at -0.72 -4.4 180)
			(layer "B.Fab")
			(effects
				(font
					(size 0.7 0.7)
					(thickness 0.15)
				)
				(justify left bottom mirror)
			)
		)
		(pad "" smd roundrect
			(at -0.349 0.002)
			(size 0.318 0.36)
			(layers "B.Paste")
			(roundrect_rratio 0.25)
		)
		(pad "" smd roundrect
			(at 0.341 0.002)
			(size 0.318 0.36)
			(layers "B.Paste")
			(roundrect_rratio 0.25)
		)
		(pad "1" smd roundrect
			(at -0.321 0.002)
			(size 0.46 0.4)
			(layers "B.Cu" "B.Mask")
			(roundrect_rratio 0.25)
			(net 1 "GND")
			(pintype "passive")
		)
		(pad "2" smd roundrect
			(at 0.32 0.002)
			(size 0.46 0.4)
			(layers "B.Cu" "B.Mask")
			(roundrect_rratio 0.25)
			(net 5 "Vref")
			(pintype "passive")
		)
	)
	(footprint "antmicro-footprints:R_0402_1005Metric"
		(layer "B.Cu")
		(at 106.19 96.8 90)
		(descr "Resistor SMD 0402")
		(tags "resistor SMD 0402")
		(property "Reference" "R76"
			(at -0.94 0.34 270)
			(layer "B.SilkS")
			(effects
				(font
					(size 0.65 0.65)
					(thickness 0.15)
				)
				(justify left bottom mirror)
			)
		)
		(property "Value" "R_0R_0402"
			(at 0 -1.4 270)
			(layer "B.Fab")
			(hide yes)
			(effects
				(font
					(size 0.7 0.7)
					(thickness 0.15)
				)
				(justify left bottom mirror)
			)
		)
		(property "Datasheet" "https://industrial.panasonic.com/cdbs/www-data/pdf/RDA0000/AOA0000C301.pdf"
			(at 0 0 90)
			(layer "F.Fab")
			(hide yes)
			(effects
				(font
					(size 1.27 1.27)
					(thickness 0.15)
				)
			)
		)
		(property "Description" "SMD Chip Resistor, Jumper, 0 ohm, 100 mW, 0402 [1005 Metric], Thick Film, General Purpose"
			(at 0 0 90)
			(layer "F.Fab")
			(hide yes)
			(effects
				(font
					(size 1.27 1.27)
					(thickness 0.15)
				)
			)
		)
		(property "Author" "Antmicro"
			(at 202.99 -9.39 0)
			(layer "B.Fab")
			(hide yes)
			(effects
				(font
					(size 1 1)
					(thickness 0.15)
				)
				(justify mirror)
			)
		)
		(property "Current" "1A"
			(at 202.99 -9.39 0)
			(layer "B.Fab")
			(hide yes)
			(effects
				(font
					(size 1 1)
					(thickness 0.15)
				)
				(justify mirror)
			)
		)
		(property "License" "Apache-2.0"
			(at 202.99 -9.39 0)
			(layer "B.Fab")
			(hide yes)
			(effects
				(font
					(size 1 1)
					(thickness 0.15)
				)
				(justify mirror)
			)
		)
		(property "MPN" "ERJ2GE0R00X"
			(at 202.99 -9.39 0)
			(layer "B.Fab")
			(hide yes)
			(effects
				(font
					(size 1 1)
					(thickness 0.15)
				)
				(justify mirror)
			)
		)
		(property "Manufacturer" "Panasonic"
			(at 202.99 -9.39 0)
			(layer "B.Fab")
			(hide yes)
			(effects
				(font
					(size 1 1)
					(thickness 0.15)
				)
				(justify mirror)
			)
		)
		(property "Tolerance" "~"
			(at 202.99 -9.39 0)
			(layer "B.Fab")
			(hide yes)
			(effects
				(font
					(size 1 1)
					(thickness 0.15)
				)
				(justify mirror)
			)
		)
		(property "Val" "0R"
			(at 202.99 -9.39 0)
			(layer "B.Fab")
			(hide yes)
			(effects
				(font
					(size 1 1)
					(thickness 0.15)
				)
				(justify mirror)
			)
		)
		(sheetname "/FPGA/")
		(sheetfile "fpga.kicad_sch")
		(attr smd)
		(fp_rect
			(start -0.925 0.47)
			(end 0.925 -0.47)
			(stroke
				(width 0.05)
				(type default)
			)
			(fill no)
			(layer "B.CrtYd")
		)
		(fp_rect
			(start -0.5 0.25)
			(end 0.5 -0.25)
			(stroke
				(width 0.15)
				(type solid)
			)
			(fill no)
			(layer "B.Fab")
		)
		(fp_text user "License: Apache-2.0"
			(at -0.95 -5.169 270)
			(layer "B.Fab")
			(effects
				(font
					(size 0.7 0.7)
					(thickness 0.15)
				)
				(justify left bottom mirror)
			)
		)
		(fp_text user "${REFERENCE}"
			(at -0.95 -3.168 270)
			(layer "B.Fab")
			(effects
				(font
					(size 0.7 0.7)
					(thickness 0.15)
				)
				(justify left bottom mirror)
			)
		)
		(fp_text user "Author: Antmicro"
			(at -0.95 -4.169 270)
			(layer "B.Fab")
			(effects
				(font
					(size 0.7 0.7)
					(thickness 0.15)
				)
				(justify left bottom mirror)
			)
		)
		(pad "1" smd roundrect
			(at -0.48 0 90)
			(size 0.59 0.64)
			(layers "B.Cu" "B.Mask" "B.Paste")
			(roundrect_rratio 0.25)
			(net 41 "/FPGA/~{FLASH_CS}")
			(pintype "passive")
		)
		(pad "2" smd roundrect
			(at 0.48 0 90)
			(size 0.59 0.64)
			(layers "B.Cu" "B.Mask" "B.Paste")
			(roundrect_rratio 0.25)
			(net 306 "Net-(U18-~{CS})")
			(pintype "passive")
		)
	)
	(footprint "antmicro-footprints:TP_SMD_0.75mm"
		(layer "B.Cu")
		(at 101.44 88.2 90)
		(property "Reference" "TP38"
			(at 0.76 0.39 90)
			(layer "B.SilkS")
			(effects
				(font
					(size 0.65 0.65)
					(thickness 0.15)
				)
				(justify right bottom mirror)
			)
		)
		(property "Value" "TP_0.75mm_SMD"
			(at 0 -1.2 90)
			(layer "B.Fab")
			(hide yes)
			(effects
				(font
					(size 0.7 0.7)
					(thickness 0.15)
				)
				(justify right bottom mirror)
			)
		)
		(property "Description" "SMT test point"
			(at 0 0 90)
			(layer "F.Fab")
			(hide yes)
			(effects
				(font
					(size 1.27 1.27)
					(thickness 0.15)
				)
			)
		)
		(property "Author" "Antmicro"
			(at 189.64 -13.24 0)
			(layer "B.Fab")
			(hide yes)
			(effects
				(font
					(size 1 1)
					(thickness 0.15)
				)
				(justify mirror)
			)
		)
		(property "License" "Apache-2.0"
			(at 189.64 -13.24 0)
			(layer "B.Fab")
			(hide yes)
			(effects
				(font
					(size 1 1)
					(thickness 0.15)
				)
				(justify mirror)
			)
		)
		(property "MPN" ""
			(at 189.64 -13.24 0)
			(layer "B.Fab")
			(hide yes)
			(effects
				(font
					(size 1 1)
					(thickness 0.15)
				)
				(justify mirror)
			)
		)
		(property "Manufacturer" ""
			(at 189.64 -13.24 0)
			(layer "B.Fab")
			(hide yes)
			(effects
				(font
					(size 1 1)
					(thickness 0.15)
				)
				(justify mirror)
			)
		)
		(sheetname "/SDI/")
		(sheetfile "sdi.kicad_sch")
		(attr exclude_from_pos_files)
		(fp_circle
			(center 0 0)
			(end 0.475 0)
			(stroke
				(width 0.05)
				(type default)
			)
			(fill no)
			(layer "B.CrtYd")
		)
		(fp_text user "${REFERENCE}"
			(at -0.4 -2.7 270)
			(layer "B.Fab")
			(effects
				(font
					(size 0.7 0.7)
					(thickness 0.15)
				)
				(justify left bottom mirror)
			)
		)
		(fp_text user "Author: Antmicro"
			(at -0.4 -3.901 270)
			(layer "B.Fab")
			(effects
				(font
					(size 0.7 0.7)
					(thickness 0.15)
				)
				(justify left bottom mirror)
			)
		)
		(fp_text user "License: Apache-2.0"
			(at -0.4 -5.101 270)
			(layer "B.Fab")
			(effects
				(font
					(size 0.7 0.7)
					(thickness 0.15)
				)
				(justify left bottom mirror)
			)
		)
		(pad "1" smd circle
			(at 0 0 90)
			(size 0.75 0.75)
			(layers "B.Cu" "B.Mask")
			(net 182 "/SDI/SDIN_TDI")
			(pinfunction "1")
			(pintype "passive")
		)
	)
)
